# T6G (Grand Teton) — schematic netlist excerpt (pin names and nets, part order shuffled) for the footprints in the layout excerpt that follows; sources: Cadence DE-HDL packaged netlist, KiCad conversion of 04192023_DAF0TMB3IC0_F0TG_MB_C_brd_V02_OCP.brd

PC83_2  Q_CAP  0.1UF 25V 10% X7R  pkg 0402  page 201 : A = PVDDCR_CPU1_P0_VCCS ; B = GND
R6058  Q_RES  0 5% CHIP  pkg 0402LF  page 139 : A = RST_PERST_OCP_V3_2_BUF2_N ; B = RST_PERST2_OCP_V3_2_N

(kicad_pcb
	(version 20260206)
	(generator "pcbnew")
	(generator_version "10.0")
	(general
		(thickness 1.6)
		(legacy_teardrops no)
	)
	(paper "A4")
	(title_block
		(title "04192023_DAF0TMB3IC0_F0TG_MB_C_brd_V02_OCP.brd")
		(comment 1 "Grand Teton / footprints 2787-2788 of 8354")
	)
	(layers
		(0 "F.Cu" signal "TOP")
		(4 "In1.Cu" signal "GND")
		(6 "In2.Cu" signal "IN1")
		(8 "In3.Cu" signal "GND1")
		(10 "In4.Cu" signal "IN2")
		(12 "In5.Cu" signal "GND2")
		(14 "In6.Cu" signal "IN3")
		(16 "In7.Cu" signal "GND3")
		(18 "In8.Cu" signal "VCC")
		(20 "In9.Cu" signal "VCC1")
		(22 "In10.Cu" signal "GND4")
		(24 "In11.Cu" signal "IN4")
		(26 "In12.Cu" signal "GND5")
		(28 "In13.Cu" signal "IN5")
		(30 "In14.Cu" signal "GND6")
		(32 "In15.Cu" signal "IN6")
		(34 "In16.Cu" signal "GND7")
		(2 "B.Cu" signal "BOTTOM")
		(9 "F.Adhes" user "F.Adhesive")
		(11 "B.Adhes" user "B.Adhesive")
		(13 "F.Paste" user "Package Geometry/Pastemask Top")
		(15 "B.Paste" user "Package Geometry/Pastemask Bottom")
		(5 "F.SilkS" user "Ref Des/Silkscreen Top")
		(7 "B.SilkS" user "Ref Des/Silkscreen Bottom")
		(1 "F.Mask" user "Board Geometry/Soldermask Top")
		(3 "B.Mask" user "Board Geometry/Soldermask Bottom")
		(17 "Dwgs.User" user "User.Drawings")
		(19 "Cmts.User" user "User.Comments")
		(21 "Eco1.User" user "User.Eco1")
		(23 "Eco2.User" user "User.Eco2")
		(25 "Edge.Cuts" user "Board Geometry/Outline")
		(27 "Margin" user)
		(31 "F.CrtYd" user "Package Geometry/Place Bound Top")
		(29 "B.CrtYd" user "Package Geometry/Place Bound Bottom")
		(35 "F.Fab" user "Ref Des/Assembly Top")
		(33 "B.Fab" user "Ref Des/Assembly Bottom")
	)
	(footprint ""
		(layer "F.Cu")
		(at 324.00748 -339.84565 90)
		(property "Reference" "PC83_2"
			(at 0 0 90)
			(layer "F.SilkS")
			(hide yes)
			(effects
				(font
					(size 1.27 1.27)
				)
			)
		)
		(property "Value" ""
			(at 0 0 90)
			(layer "F.Fab")
			(effects
				(font
					(size 1.27 1.27)
				)
			)
		)
		(duplicate_pad_numbers_are_jumpers no)
		(fp_line
			(start 0.7874 -0.4064)
			(end 0.7874 0.4064)
			(stroke
				(width 0.1524)
				(type default)
			)
			(layer "F.SilkS")
		)
		(fp_line
			(start -0.7874 -0.4064)
			(end 0.7874 -0.4064)
			(stroke
				(width 0.1524)
				(type default)
			)
			(layer "F.SilkS")
		)
		(fp_line
			(start 0.7874 0.4064)
			(end -0.7874 0.4064)
			(stroke
				(width 0.1524)
				(type default)
			)
			(layer "F.SilkS")
		)
		(fp_line
			(start -0.7874 0.4064)
			(end -0.7874 -0.4064)
			(stroke
				(width 0.1524)
				(type default)
			)
			(layer "F.SilkS")
		)
		(fp_line
			(start -0.12065 -0.305054)
			(end -0.12065 -0.2794)
			(stroke
				(width 0.1)
				(type default)
			)
			(layer "F.Fab")
		)
		(fp_line
			(start -0.67945 -0.305054)
			(end -0.12065 -0.305054)
			(stroke
				(width 0.1)
				(type default)
			)
			(layer "F.Fab")
		)
		(fp_line
			(start 0.67945 -0.3048)
			(end 0.67945 0.3048)
			(stroke
				(width 0.1)
				(type default)
			)
			(layer "F.Fab")
		)
		(fp_line
			(start 0.12065 -0.3048)
			(end 0.67945 -0.3048)
			(stroke
				(width 0.1)
				(type default)
			)
			(layer "F.Fab")
		)
		(fp_line
			(start 0.12065 -0.2794)
			(end 0.12065 -0.3048)
			(stroke
				(width 0.1)
				(type default)
			)
			(layer "F.Fab")
		)
		(fp_line
			(start -0.12065 -0.2794)
			(end 0.12065 -0.2794)
			(stroke
				(width 0.1)
				(type default)
			)
			(layer "F.Fab")
		)
		(fp_line
			(start 0.120396 0.2794)
			(end -0.12065 0.2794)
			(stroke
				(width 0.1)
				(type default)
			)
			(layer "F.Fab")
		)
		(fp_line
			(start -0.12065 0.2794)
			(end -0.12065 0.3048)
			(stroke
				(width 0.1)
				(type default)
			)
			(layer "F.Fab")
		)
		(fp_line
			(start 0.67945 0.3048)
			(end 0.120396 0.3048)
			(stroke
				(width 0.1)
				(type default)
			)
			(layer "F.Fab")
		)
		(fp_line
			(start 0.120396 0.3048)
			(end 0.120396 0.2794)
			(stroke
				(width 0.1)
				(type default)
			)
			(layer "F.Fab")
		)
		(fp_line
			(start -0.12065 0.3048)
			(end -0.67945 0.3048)
			(stroke
				(width 0.1)
				(type default)
			)
			(layer "F.Fab")
		)
		(fp_line
			(start -0.67945 0.3048)
			(end -0.67945 -0.305054)
			(stroke
				(width 0.1)
				(type default)
			)
			(layer "F.Fab")
		)
		(pad "1" smd circle
			(at -0.40005 0 90)
			(size 0 0)
			(layers "F.Cu" "F.Mask" "F.Paste")
			(net "PVDDCR_CPU1_P0_VCCS")
		)
		(pad "2" smd circle
			(at 0.40005 0 90)
			(size 0 0)
			(layers "F.Cu" "F.Mask" "F.Paste")
			(net "GND")
		)
	)
	(footprint ""
		(layer "F.Cu")
		(at 83.222084 -37.36848 180)
		(property "Reference" "R6058"
			(at 0 0 180)
			(layer "F.SilkS")
			(hide yes)
			(effects
				(font
					(size 1.27 1.27)
				)
			)
		)
		(property "Value" ""
			(at 0 0 180)
			(layer "F.Fab")
			(effects
				(font
					(size 1.27 1.27)
				)
			)
		)
		(duplicate_pad_numbers_are_jumpers no)
		(fp_line
			(start 0.7874 0.4064)
			(end -0.7874 0.4064)
			(stroke
				(width 0.1524)
				(type default)
			)
			(layer "F.SilkS")
		)
		(fp_line
			(start 0.7874 -0.4064)
			(end 0.7874 0.4064)
			(stroke
				(width 0.1524)
				(type default)
			)
			(layer "F.SilkS")
		)
		(fp_line
			(start -0.7874 0.4064)
			(end -0.7874 -0.4064)
			(stroke
				(width 0.1524)
				(type default)
			)
			(layer "F.SilkS")
		)
		(fp_line
			(start -0.7874 -0.4064)
			(end 0.7874 -0.4064)
			(stroke
				(width 0.1524)
				(type default)
			)
			(layer "F.SilkS")
		)
		(fp_line
			(start 0.67945 0.3048)
			(end 0.120396 0.3048)
			(stroke
				(width 0.1)
				(type default)
			)
			(layer "F.Fab")
		)
		(fp_line
			(start 0.67945 -0.3048)
			(end 0.67945 0.3048)
			(stroke
				(width 0.1)
				(type default)
			)
			(layer "F.Fab")
		)
		(fp_line
			(start 0.12065 -0.2794)
			(end 0.12065 -0.3048)
			(stroke
				(width 0.1)
				(type default)
			)
			(layer "F.Fab")
		)
		(fp_line
			(start 0.12065 -0.3048)
			(end 0.67945 -0.3048)
			(stroke
				(width 0.1)
				(type default)
			)
			(layer "F.Fab")
		)
		(fp_line
			(start 0.120396 0.3048)
			(end 0.120396 0.2794)
			(stroke
				(width 0.1)
				(type default)
			)
			(layer "F.Fab")
		)
		(fp_line
			(start 0.120396 0.2794)
			(end -0.12065 0.2794)
			(stroke
				(width 0.1)
				(type default)
			)
			(layer "F.Fab")
		)
		(fp_line
			(start -0.12065 0.3048)
			(end -0.67945 0.3048)
			(stroke
				(width 0.1)
				(type default)
			)
			(layer "F.Fab")
		)
		(fp_line
			(start -0.12065 0.2794)
			(end -0.12065 0.3048)
			(stroke
				(width 0.1)
				(type default)
			)
			(layer "F.Fab")
		)
		(fp_line
			(start -0.12065 -0.2794)
			(end 0.12065 -0.2794)
			(stroke
				(width 0.1)
				(type default)
			)
			(layer "F.Fab")
		)
		(fp_line
			(start -0.12065 -0.305054)
			(end -0.12065 -0.2794)
			(stroke
				(width 0.1)
				(type default)
			)
			(layer "F.Fab")
		)
		(fp_line
			(start -0.67945 0.3048)
			(end -0.67945 -0.305054)
			(stroke
				(width 0.1)
				(type default)
			)
			(layer "F.Fab")
		)
		(fp_line
			(start -0.67945 -0.305054)
			(end -0.12065 -0.305054)
			(stroke
				(width 0.1)
				(type default)
			)
			(layer "F.Fab")
		)
		(pad "1" smd circle
			(at -0.40005 0 180)
			(size 0 0)
			(layers "F.Cu" "F.Mask" "F.Paste")
			(net "RST_PERST_OCP_V3_2_BUF2_N")
		)
		(pad "2" smd circle
			(at 0.40005 0 180)
			(size 0 0)
			(layers "F.Cu" "F.Mask" "F.Paste")
			(net "RST_PERST2_OCP_V3_2_N")
		)
	)
)
